# S9S_MB_2U (Grand Teton) — schematic netlist excerpt (pin names and nets, part order shuffled) for the footprints in the layout excerpt that follows; sources: Cadence DE-HDL packaged netlist, KiCad conversion of 03242023_DA0F0TMBIJ0_F0T_Motherboard_J_brd_V01_OCP.brd

PC537_P1_4  Q_CAP  22UF 16V 20% X6S  pkg C0805  page 286 : A = SW_P12V_PVCCIN_CPU1_FLT ; B = GND
PR136  Q_RES  0 5% CHIP  pkg 0402LF  page 270 : A = PVCCIN_CPU0_VOS8 ; B = PVCCIN_CPU0
R258  Q_RES  240 1% CHIP  pkg 0402LF  page 120 : A = PVNN_TERM_CPU1 ; B = PUD_PCH_BOOT_MODE_CPU1

(kicad_pcb
	(version 20260206)
	(generator "pcbnew")
	(generator_version "10.0")
	(general
		(thickness 1.6)
		(legacy_teardrops no)
	)
	(paper "A4")
	(title_block
		(title "03242023_DA0F0TMBIJ0_F0T_Motherboard_J_brd_V01_OCP.brd")
		(comment 1 "Grand Teton / footprints 5380-5382 of 6105")
	)
	(layers
		(0 "F.Cu" signal "TOP")
		(4 "In1.Cu" signal "GND")
		(6 "In2.Cu" signal "IN1")
		(8 "In3.Cu" signal "GND1")
		(10 "In4.Cu" signal "IN2")
		(12 "In5.Cu" signal "GND2")
		(14 "In6.Cu" signal "IN3")
		(16 "In7.Cu" signal "GND3")
		(18 "In8.Cu" signal "VCC")
		(20 "In9.Cu" signal "VCC1")
		(22 "In10.Cu" signal "GND4")
		(24 "In11.Cu" signal "IN4")
		(26 "In12.Cu" signal "GND5")
		(28 "In13.Cu" signal "IN5")
		(30 "In14.Cu" signal "GND6")
		(32 "In15.Cu" signal "IN6")
		(34 "In16.Cu" signal "GND7")
		(2 "B.Cu" signal "BOTTOM")
		(9 "F.Adhes" user "F.Adhesive")
		(11 "B.Adhes" user "B.Adhesive")
		(13 "F.Paste" user "Package Geometry/Pastemask Top")
		(15 "B.Paste" user "Package Geometry/Pastemask Bottom")
		(5 "F.SilkS" user "Ref Des/Silkscreen Top")
		(7 "B.SilkS" user "Ref Des/Silkscreen Bottom")
		(1 "F.Mask" user "Board Geometry/Soldermask Top")
		(3 "B.Mask" user "Board Geometry/Soldermask Bottom")
		(17 "Dwgs.User" user "User.Drawings")
		(19 "Cmts.User" user "User.Comments")
		(21 "Eco1.User" user "User.Eco1")
		(23 "Eco2.User" user "User.Eco2")
		(25 "Edge.Cuts" user "Board Geometry/Outline")
		(27 "Margin" user)
		(31 "F.CrtYd" user "Package Geometry/Place Bound Top")
		(29 "B.CrtYd" user "Package Geometry/Place Bound Bottom")
		(35 "F.Fab" user "Ref Des/Assembly Top")
		(33 "B.Fab" user "Ref Des/Assembly Bottom")
	)
	(footprint ""
		(layer "B.Cu")
		(at 382.28778 -345.463114 -90)
		(property "Reference" "PR136"
			(at 0 0 90)
			(layer "B.SilkS")
			(hide yes)
			(effects
				(font
					(size 1.27 1.27)
				)
				(justify mirror)
			)
		)
		(property "Value" ""
			(at 0 0 90)
			(layer "B.Fab")
			(effects
				(font
					(size 1.27 1.27)
				)
				(justify mirror)
			)
		)
		(duplicate_pad_numbers_are_jumpers no)
		(fp_line
			(start -0.7874 0.4064)
			(end 0.7874 0.4064)
			(stroke
				(width 0.1524)
				(type default)
			)
			(layer "B.SilkS")
		)
		(fp_line
			(start 0.7874 0.4064)
			(end 0.7874 -0.4064)
			(stroke
				(width 0.1524)
				(type default)
			)
			(layer "B.SilkS")
		)
		(fp_line
			(start -0.7874 -0.4064)
			(end -0.7874 0.4064)
			(stroke
				(width 0.1524)
				(type default)
			)
			(layer "B.SilkS")
		)
		(fp_line
			(start 0.7874 -0.4064)
			(end -0.7874 -0.4064)
			(stroke
				(width 0.1524)
				(type default)
			)
			(layer "B.SilkS")
		)
		(fp_line
			(start -0.67945 0.3048)
			(end -0.120396 0.3048)
			(stroke
				(width 0.1)
				(type default)
			)
			(layer "B.Fab")
		)
		(fp_line
			(start -0.120396 0.3048)
			(end -0.120396 0.2794)
			(stroke
				(width 0.1)
				(type default)
			)
			(layer "B.Fab")
		)
		(fp_line
			(start 0.12065 0.3048)
			(end 0.67945 0.3048)
			(stroke
				(width 0.1)
				(type default)
			)
			(layer "B.Fab")
		)
		(fp_line
			(start 0.67945 0.3048)
			(end 0.67945 -0.305054)
			(stroke
				(width 0.1)
				(type default)
			)
			(layer "B.Fab")
		)
		(fp_line
			(start -0.120396 0.2794)
			(end 0.12065 0.2794)
			(stroke
				(width 0.1)
				(type default)
			)
			(layer "B.Fab")
		)
		(fp_line
			(start 0.12065 0.2794)
			(end 0.12065 0.3048)
			(stroke
				(width 0.1)
				(type default)
			)
			(layer "B.Fab")
		)
		(fp_line
			(start -0.12065 -0.2794)
			(end -0.12065 -0.3048)
			(stroke
				(width 0.1)
				(type default)
			)
			(layer "B.Fab")
		)
		(fp_line
			(start 0.12065 -0.2794)
			(end -0.12065 -0.2794)
			(stroke
				(width 0.1)
				(type default)
			)
			(layer "B.Fab")
		)
		(fp_line
			(start -0.67945 -0.3048)
			(end -0.67945 0.3048)
			(stroke
				(width 0.1)
				(type default)
			)
			(layer "B.Fab")
		)
		(fp_line
			(start -0.12065 -0.3048)
			(end -0.67945 -0.3048)
			(stroke
				(width 0.1)
				(type default)
			)
			(layer "B.Fab")
		)
		(fp_line
			(start 0.12065 -0.305054)
			(end 0.12065 -0.2794)
			(stroke
				(width 0.1)
				(type default)
			)
			(layer "B.Fab")
		)
		(fp_line
			(start 0.67945 -0.305054)
			(end 0.12065 -0.305054)
			(stroke
				(width 0.1)
				(type default)
			)
			(layer "B.Fab")
		)
		(pad "1" smd circle
			(at 0.40005 0 90)
			(size 0 0)
			(layers "B.Cu" "B.Mask" "B.Paste")
			(net "PVCCIN_CPU0_VOS8")
		)
		(pad "2" smd circle
			(at -0.40005 0 90)
			(size 0 0)
			(layers "B.Cu" "B.Mask" "B.Paste")
			(net "PVCCIN_CPU0")
		)
	)
	(footprint ""
		(layer "B.Cu")
		(at 176.10074 -192.699894 -90)
		(property "Reference" "R258"
			(at 0 0 90)
			(layer "B.SilkS")
			(hide yes)
			(effects
				(font
					(size 1.27 1.27)
				)
				(justify mirror)
			)
		)
		(property "Value" ""
			(at 0 0 90)
			(layer "B.Fab")
			(effects
				(font
					(size 1.27 1.27)
				)
				(justify mirror)
			)
		)
		(duplicate_pad_numbers_are_jumpers no)
		(fp_line
			(start -0.7874 0.4064)
			(end 0.7874 0.4064)
			(stroke
				(width 0.1524)
				(type default)
			)
			(layer "B.SilkS")
		)
		(fp_line
			(start 0.7874 0.4064)
			(end 0.7874 -0.4064)
			(stroke
				(width 0.1524)
				(type default)
			)
			(layer "B.SilkS")
		)
		(fp_line
			(start -0.7874 -0.4064)
			(end -0.7874 0.4064)
			(stroke
				(width 0.1524)
				(type default)
			)
			(layer "B.SilkS")
		)
		(fp_line
			(start 0.7874 -0.4064)
			(end -0.7874 -0.4064)
			(stroke
				(width 0.1524)
				(type default)
			)
			(layer "B.SilkS")
		)
		(fp_line
			(start -0.67945 0.3048)
			(end -0.120396 0.3048)
			(stroke
				(width 0.1)
				(type default)
			)
			(layer "B.Fab")
		)
		(fp_line
			(start -0.120396 0.3048)
			(end -0.120396 0.2794)
			(stroke
				(width 0.1)
				(type default)
			)
			(layer "B.Fab")
		)
		(fp_line
			(start 0.12065 0.3048)
			(end 0.67945 0.3048)
			(stroke
				(width 0.1)
				(type default)
			)
			(layer "B.Fab")
		)
		(fp_line
			(start 0.67945 0.3048)
			(end 0.67945 -0.305054)
			(stroke
				(width 0.1)
				(type default)
			)
			(layer "B.Fab")
		)
		(fp_line
			(start -0.120396 0.2794)
			(end 0.12065 0.2794)
			(stroke
				(width 0.1)
				(type default)
			)
			(layer "B.Fab")
		)
		(fp_line
			(start 0.12065 0.2794)
			(end 0.12065 0.3048)
			(stroke
				(width 0.1)
				(type default)
			)
			(layer "B.Fab")
		)
		(fp_line
			(start -0.12065 -0.2794)
			(end -0.12065 -0.3048)
			(stroke
				(width 0.1)
				(type default)
			)
			(layer "B.Fab")
		)
		(fp_line
			(start 0.12065 -0.2794)
			(end -0.12065 -0.2794)
			(stroke
				(width 0.1)
				(type default)
			)
			(layer "B.Fab")
		)
		(fp_line
			(start -0.67945 -0.3048)
			(end -0.67945 0.3048)
			(stroke
				(width 0.1)
				(type default)
			)
			(layer "B.Fab")
		)
		(fp_line
			(start -0.12065 -0.3048)
			(end -0.67945 -0.3048)
			(stroke
				(width 0.1)
				(type default)
			)
			(layer "B.Fab")
		)
		(fp_line
			(start 0.12065 -0.305054)
			(end 0.12065 -0.2794)
			(stroke
				(width 0.1)
				(type default)
			)
			(layer "B.Fab")
		)
		(fp_line
			(start 0.67945 -0.305054)
			(end 0.12065 -0.305054)
			(stroke
				(width 0.1)
				(type default)
			)
			(layer "B.Fab")
		)
		(pad "1" smd circle
			(at 0.40005 0 90)
			(size 0 0)
			(layers "B.Cu" "B.Mask" "B.Paste")
			(net "PVNN_TERM_CPU1")
		)
		(pad "2" smd circle
			(at -0.40005 0 90)
			(size 0 0)
			(layers "B.Cu" "B.Mask" "B.Paste")
			(net "PUD_PCH_BOOT_MODE_CPU1")
		)
	)
	(footprint ""
		(layer "B.Cu")
		(at 122.600974 -333.73568 90)
		(property "Reference" "PC537_P1_4"
			(at 0 0 90)
			(layer "B.SilkS")
			(hide yes)
			(effects
				(font
					(size 1.27 1.27)
				)
				(justify mirror)
			)
		)
		(property "Value" ""
			(at 0 0 90)
			(layer "B.Fab")
			(effects
				(font
					(size 1.27 1.27)
				)
				(justify mirror)
			)
		)
		(duplicate_pad_numbers_are_jumpers no)
		(fp_line
			(start 1.524 -0.762)
			(end -1.524 -0.762)
			(stroke
				(width 0.1524)
				(type default)
			)
			(layer "B.SilkS")
		)
		(fp_line
			(start -1.524 -0.762)
			(end -1.524 0.762)
			(stroke
				(width 0.1524)
				(type default)
			)
			(layer "B.SilkS")
		)
		(fp_line
			(start 1.524 0.762)
			(end 1.524 -0.762)
			(stroke
				(width 0.1524)
				(type default)
			)
			(layer "B.SilkS")
		)
		(fp_line
			(start -1.524 0.762)
			(end 1.524 0.762)
			(stroke
				(width 0.1524)
				(type default)
			)
			(layer "B.SilkS")
		)
		(fp_line
			(start 1.1049 -0.724916)
			(end 1.1049 0.724916)
			(stroke
				(width 0.1)
				(type default)
			)
			(layer "B.Fab")
		)
		(fp_line
			(start -1.1049 -0.724916)
			(end 1.1049 -0.724916)
			(stroke
				(width 0.1)
				(type default)
			)
			(layer "B.Fab")
		)
		(fp_line
			(start 1.1049 0.724916)
			(end -1.1049 0.724916)
			(stroke
				(width 0.1)
				(type default)
			)
			(layer "B.Fab")
		)
		(fp_line
			(start -1.1049 0.724916)
			(end -1.1049 -0.724916)
			(stroke
				(width 0.1)
				(type default)
			)
			(layer "B.Fab")
		)
		(pad "1" smd rect
			(at 0.889 0 90)
			(size 1.016 1.27)
			(layers "B.Cu" "B.Mask" "B.Paste")
			(net "SW_P12V_PVCCIN_CPU1_FLT")
		)
		(pad "2" smd rect
			(at -0.889 0 90)
			(size 1.016 1.27)
			(layers "B.Cu" "B.Mask" "B.Paste")
			(net "GND")
		)
	)
)
